(kicad_pcb
	(version 20260206)
	(generator "pcbnew")
	(generator_version "10.0")
	(general
		(thickness 1.6)
		(legacy_teardrops no)
	)
	(paper "A4")
	(title_block
		(title "01162023_DA0F0TEBIF0_F0T_Expander_BD_F_brd_V02_OCP.brd")
		(comment 1 "Grand Teton / footprints 7814-7821 of 9728")
	)
	(layers
		(0 "F.Cu" signal "TOP")
		(4 "In1.Cu" signal "GND")
		(6 "In2.Cu" signal "VCC")
		(8 "In3.Cu" signal "VCC1")
		(10 "In4.Cu" signal "GND1")
		(12 "In5.Cu" signal "IN1")
		(14 "In6.Cu" signal "GND2")
		(16 "In7.Cu" signal "IN2")
		(18 "In8.Cu" signal "GND3")
		(20 "In9.Cu" signal "IN3")
		(22 "In10.Cu" signal "GND4")
		(24 "In11.Cu" signal "IN4")
		(26 "In12.Cu" signal "GND5")
		(28 "In13.Cu" signal "IN5")
		(30 "In14.Cu" signal "GND6")
		(32 "In15.Cu" signal "IN6")
		(34 "In16.Cu" signal "GND7")
		(2 "B.Cu" signal "BOTTOM")
		(9 "F.Adhes" user "F.Adhesive")
		(11 "B.Adhes" user "B.Adhesive")
		(13 "F.Paste" user "Package Geometry/Pastemask Top")
		(15 "B.Paste" user "Package Geometry/Pastemask Bottom")
		(5 "F.SilkS" user "Ref Des/Silkscreen Top")
		(7 "B.SilkS" user "Ref Des/Silkscreen Bottom")
		(1 "F.Mask" user "Board Geometry/Soldermask Top")
		(3 "B.Mask" user "Board Geometry/Soldermask Bottom")
		(17 "Dwgs.User" user "User.Drawings")
		(19 "Cmts.User" user "User.Comments")
		(21 "Eco1.User" user "User.Eco1")
		(23 "Eco2.User" user "User.Eco2")
		(25 "Edge.Cuts" user "Board Geometry/Outline")
		(27 "Margin" user)
		(31 "F.CrtYd" user "Package Geometry/Place Bound Top")
		(29 "B.CrtYd" user "Package Geometry/Place Bound Bottom")
		(35 "F.Fab" user "Ref Des/Assembly Top")
		(33 "B.Fab" user "Ref Des/Assembly Bottom")
	)
	(footprint ""
		(layer "B.Cu")
		(at 19.67611 -222.214186)
		(property "Reference" "R3449"
			(at 0 0 0)
			(layer "B.SilkS")
			(hide yes)
			(effects
				(font
					(size 1.27 1.27)
				)
				(justify mirror)
			)
		)
		(property "Value" ""
			(at 0 0 0)
			(layer "B.Fab")
			(effects
				(font
					(size 1.27 1.27)
				)
				(justify mirror)
			)
		)
		(duplicate_pad_numbers_are_jumpers no)
		(fp_line
			(start -0.7874 -0.4064)
			(end -0.7874 0.4064)
			(stroke
				(width 0.1524)
				(type default)
			)
			(layer "B.SilkS")
		)
		(fp_line
			(start -0.7874 0.4064)
			(end 0.7874 0.4064)
			(stroke
				(width 0.1524)
				(type default)
			)
			(layer "B.SilkS")
		)
		(fp_line
			(start 0.7874 -0.4064)
			(end -0.7874 -0.4064)
			(stroke
				(width 0.1524)
				(type default)
			)
			(layer "B.SilkS")
		)
		(fp_line
			(start 0.7874 0.4064)
			(end 0.7874 -0.4064)
			(stroke
				(width 0.1524)
				(type default)
			)
			(layer "B.SilkS")
		)
		(fp_line
			(start -0.67945 -0.3048)
			(end -0.67945 0.3048)
			(stroke
				(width 0.1)
				(type default)
			)
			(layer "B.Fab")
		)
		(fp_line
			(start -0.67945 0.3048)
			(end -0.120396 0.3048)
			(stroke
				(width 0.1)
				(type default)
			)
			(layer "B.Fab")
		)
		(fp_line
			(start -0.12065 -0.3048)
			(end -0.67945 -0.3048)
			(stroke
				(width 0.1)
				(type default)
			)
			(layer "B.Fab")
		)
		(fp_line
			(start -0.12065 -0.2794)
			(end -0.12065 -0.3048)
			(stroke
				(width 0.1)
				(type default)
			)
			(layer "B.Fab")
		)
		(fp_line
			(start -0.120396 0.2794)
			(end 0.12065 0.2794)
			(stroke
				(width 0.1)
				(type default)
			)
			(layer "B.Fab")
		)
		(fp_line
			(start -0.120396 0.3048)
			(end -0.120396 0.2794)
			(stroke
				(width 0.1)
				(type default)
			)
			(layer "B.Fab")
		)
		(fp_line
			(start 0.12065 -0.305054)
			(end 0.12065 -0.2794)
			(stroke
				(width 0.1)
				(type default)
			)
			(layer "B.Fab")
		)
		(fp_line
			(start 0.12065 -0.2794)
			(end -0.12065 -0.2794)
			(stroke
				(width 0.1)
				(type default)
			)
			(layer "B.Fab")
		)
		(fp_line
			(start 0.12065 0.2794)
			(end 0.12065 0.3048)
			(stroke
				(width 0.1)
				(type default)
			)
			(layer "B.Fab")
		)
		(fp_line
			(start 0.12065 0.3048)
			(end 0.67945 0.3048)
			(stroke
				(width 0.1)
				(type default)
			)
			(layer "B.Fab")
		)
		(fp_line
			(start 0.67945 -0.305054)
			(end 0.12065 -0.305054)
			(stroke
				(width 0.1)
				(type default)
			)
			(layer "B.Fab")
		)
		(fp_line
			(start 0.67945 0.3048)
			(end 0.67945 -0.305054)
			(stroke
				(width 0.1)
				(type default)
			)
			(layer "B.Fab")
		)
		(pad "1" smd circle
			(at 0.40005 0 180)
			(size 0 0)
			(layers "B.Cu" "B.Mask" "B.Paste")
			(net "SPI_PEX0_SDIO0_MUX")
		)
		(pad "2" smd circle
			(at -0.40005 0 180)
			(size 0 0)
			(layers "B.Cu" "B.Mask" "B.Paste")
			(net "SPI_PEX0_SDIO0_MUX_R")
		)
	)
	(footprint ""
		(layer "B.Cu")
		(at 25.134824 -259.341112)
		(property "Reference" "C3072"
			(at 0 0 0)
			(layer "B.SilkS")
			(hide yes)
			(effects
				(font
					(size 1.27 1.27)
				)
				(justify mirror)
			)
		)
		(property "Value" ""
			(at 0 0 0)
			(layer "B.Fab")
			(effects
				(font
					(size 1.27 1.27)
				)
				(justify mirror)
			)
		)
		(duplicate_pad_numbers_are_jumpers no)
		(fp_line
			(start -0.299974 -0.150114)
			(end -0.299974 0.150114)
			(stroke
				(width 0.1)
				(type default)
			)
			(layer "B.Fab")
		)
		(fp_line
			(start -0.299974 0.150114)
			(end 0.299974 0.150114)
			(stroke
				(width 0.1)
				(type default)
			)
			(layer "B.Fab")
		)
		(fp_line
			(start 0.299974 -0.150114)
			(end -0.299974 -0.150114)
			(stroke
				(width 0.1)
				(type default)
			)
			(layer "B.Fab")
		)
		(fp_line
			(start 0.299974 0.150114)
			(end 0.299974 -0.150114)
			(stroke
				(width 0.1)
				(type default)
			)
			(layer "B.Fab")
		)
		(pad "1" smd rect
			(at 0.2667 0 180)
			(size 0.3048 0.381)
			(layers "B.Cu" "B.Mask" "B.Paste")
			(net "P1V8_VDDA_PEX0")
		)
		(pad "2" smd rect
			(at -0.2667 0 180)
			(size 0.3048 0.381)
			(layers "B.Cu" "B.Mask" "B.Paste")
			(net "GND")
		)
	)
	(footprint ""
		(layer "B.Cu")
		(at 339.693758 -220.387164 -90)
		(property "Reference" "C2083"
			(at 0 0 90)
			(layer "B.SilkS")
			(hide yes)
			(effects
				(font
					(size 1.27 1.27)
				)
				(justify mirror)
			)
		)
		(property "Value" ""
			(at 0 0 90)
			(layer "B.Fab")
			(effects
				(font
					(size 1.27 1.27)
				)
				(justify mirror)
			)
		)
		(duplicate_pad_numbers_are_jumpers no)
		(fp_line
			(start -0.69215 0.2921)
			(end 0.69215 0.2921)
			(stroke
				(width 0.1524)
				(type default)
			)
			(layer "B.SilkS")
		)
		(fp_line
			(start 0.69215 0.2921)
			(end 0.69215 -0.2921)
			(stroke
				(width 0.1524)
				(type default)
			)
			(layer "B.SilkS")
		)
		(fp_line
			(start -0.69215 -0.2921)
			(end -0.69215 0.2921)
			(stroke
				(width 0.1524)
				(type default)
			)
			(layer "B.SilkS")
		)
		(fp_line
			(start 0.69215 -0.2921)
			(end -0.69215 -0.2921)
			(stroke
				(width 0.1524)
				(type default)
			)
			(layer "B.SilkS")
		)
		(fp_line
			(start -0.51435 0.2794)
			(end 0.51435 0.2794)
			(stroke
				(width 0.1)
				(type default)
			)
			(layer "B.Fab")
		)
		(fp_line
			(start 0.51435 0.2794)
			(end 0.51435 -0.2794)
			(stroke
				(width 0.1)
				(type default)
			)
			(layer "B.Fab")
		)
		(fp_line
			(start -0.51435 -0.2794)
			(end -0.51435 0.2794)
			(stroke
				(width 0.1)
				(type default)
			)
			(layer "B.Fab")
		)
		(fp_line
			(start 0.51435 -0.2794)
			(end -0.51435 -0.2794)
			(stroke
				(width 0.1)
				(type default)
			)
			(layer "B.Fab")
		)
		(pad "1" smd circle
			(at 0.40005 0 90)
			(size 0 0)
			(layers "B.Cu" "B.Mask" "B.Paste")
			(net "P3V3_FPGA_VCCIO4")
		)
		(pad "2" smd circle
			(at -0.40005 0 90)
			(size 0 0)
			(layers "B.Cu" "B.Mask" "B.Paste")
			(net "GND")
		)
		(zone
			(layer "B.Cu")
			(hatch none 0.5)
			(connect_pads
				(clearance 0)
			)
			(min_thickness 0.25)
			(keepout
				(tracks not_allowed)
				(vias allowed)
				(pads allowed)
				(copperpour not_allowed)
				(footprints allowed)
			)
			(placement
				(enabled no)
				(sheetname "")
			)
			(fill
				(thermal_gap 0.5)
				(thermal_bridge_width 0.5)
				(island_removal_mode 0)
			)
			(polygon
				(pts
					(xy 339.606128 -220.196664) (xy 339.547962 -220.288104) (xy 339.547962 -220.487494) (xy 339.606128 -220.577664)
					(xy 339.781388 -220.577664) (xy 339.839808 -220.487494) (xy 339.839808 -220.288104) (xy 339.781642 -220.196664)
				)
			)
		)
	)
	(footprint ""
		(layer "B.Cu")
		(at 239.264698 -217.330528 -90)
		(property "Reference" "R4854"
			(at 0 0 90)
			(layer "B.SilkS")
			(hide yes)
			(effects
				(font
					(size 1.27 1.27)
				)
				(justify mirror)
			)
		)
		(property "Value" ""
			(at 0 0 90)
			(layer "B.Fab")
			(effects
				(font
					(size 1.27 1.27)
				)
				(justify mirror)
			)
		)
		(duplicate_pad_numbers_are_jumpers no)
		(fp_line
			(start -0.7874 0.4064)
			(end 0.7874 0.4064)
			(stroke
				(width 0.1524)
				(type default)
			)
			(layer "B.SilkS")
		)
		(fp_line
			(start 0.7874 0.4064)
			(end 0.7874 -0.4064)
			(stroke
				(width 0.1524)
				(type default)
			)
			(layer "B.SilkS")
		)
		(fp_line
			(start -0.7874 -0.4064)
			(end -0.7874 0.4064)
			(stroke
				(width 0.1524)
				(type default)
			)
			(layer "B.SilkS")
		)
		(fp_line
			(start 0.7874 -0.4064)
			(end -0.7874 -0.4064)
			(stroke
				(width 0.1524)
				(type default)
			)
			(layer "B.SilkS")
		)
		(fp_line
			(start -0.67945 0.3048)
			(end -0.120396 0.3048)
			(stroke
				(width 0.1)
				(type default)
			)
			(layer "B.Fab")
		)
		(fp_line
			(start -0.120396 0.3048)
			(end -0.120396 0.2794)
			(stroke
				(width 0.1)
				(type default)
			)
			(layer "B.Fab")
		)
		(fp_line
			(start 0.12065 0.3048)
			(end 0.67945 0.3048)
			(stroke
				(width 0.1)
				(type default)
			)
			(layer "B.Fab")
		)
		(fp_line
			(start 0.67945 0.3048)
			(end 0.67945 -0.305054)
			(stroke
				(width 0.1)
				(type default)
			)
			(layer "B.Fab")
		)
		(fp_line
			(start -0.120396 0.2794)
			(end 0.12065 0.2794)
			(stroke
				(width 0.1)
				(type default)
			)
			(layer "B.Fab")
		)
		(fp_line
			(start 0.12065 0.2794)
			(end 0.12065 0.3048)
			(stroke
				(width 0.1)
				(type default)
			)
			(layer "B.Fab")
		)
		(fp_line
			(start -0.12065 -0.2794)
			(end -0.12065 -0.3048)
			(stroke
				(width 0.1)
				(type default)
			)
			(layer "B.Fab")
		)
		(fp_line
			(start 0.12065 -0.2794)
			(end -0.12065 -0.2794)
			(stroke
				(width 0.1)
				(type default)
			)
			(layer "B.Fab")
		)
		(fp_line
			(start -0.67945 -0.3048)
			(end -0.67945 0.3048)
			(stroke
				(width 0.1)
				(type default)
			)
			(layer "B.Fab")
		)
		(fp_line
			(start -0.12065 -0.3048)
			(end -0.67945 -0.3048)
			(stroke
				(width 0.1)
				(type default)
			)
			(layer "B.Fab")
		)
		(fp_line
			(start 0.12065 -0.305054)
			(end 0.12065 -0.2794)
			(stroke
				(width 0.1)
				(type default)
			)
			(layer "B.Fab")
		)
		(fp_line
			(start 0.67945 -0.305054)
			(end 0.12065 -0.305054)
			(stroke
				(width 0.1)
				(type default)
			)
			(layer "B.Fab")
		)
		(pad "1" smd circle
			(at 0.40005 0 90)
			(size 0 0)
			(layers "B.Cu" "B.Mask" "B.Paste")
			(net "P1V2_AUX")
		)
		(pad "2" smd circle
			(at -0.40005 0 90)
			(size 0 0)
			(layers "B.Cu" "B.Mask" "B.Paste")
			(net "P1V2_BIC_ADCVREFREXT0")
		)
	)
	(footprint ""
		(layer "B.Cu")
		(at 238.514382 -215.740742 180)
		(property "Reference" "L1"
			(at 0 0 0)
			(layer "B.SilkS")
			(hide yes)
			(effects
				(font
					(size 1.27 1.27)
				)
				(justify mirror)
			)
		)
		(property "Value" ""
			(at 0 0 0)
			(layer "B.Fab")
			(effects
				(font
					(size 1.27 1.27)
				)
				(justify mirror)
			)
		)
		(duplicate_pad_numbers_are_jumpers no)
		(fp_line
			(start 1.27 0.5842)
			(end 1.27 -0.5842)
			(stroke
				(width 0.1524)
				(type default)
			)
			(layer "B.SilkS")
		)
		(fp_line
			(start 1.27 -0.5588)
			(end 1.27 -0.5842)
			(stroke
				(width 0.1524)
				(type default)
			)
			(layer "B.SilkS")
		)
		(fp_line
			(start 1.27 -0.5842)
			(end -1.27 -0.5842)
			(stroke
				(width 0.1524)
				(type default)
			)
			(layer "B.SilkS")
		)
		(fp_line
			(start -1.27 0.5842)
			(end 1.27 0.5842)
			(stroke
				(width 0.1524)
				(type default)
			)
			(layer "B.SilkS")
		)
		(fp_line
			(start -1.27 0.5842)
			(end -1.27 -0.5842)
			(stroke
				(width 0.1524)
				(type default)
			)
			(layer "B.SilkS")
		)
		(fp_line
			(start 1.194308 0.406654)
			(end 1.194308 -0.406654)
			(stroke
				(width 0.1)
				(type default)
			)
			(layer "B.Fab")
		)
		(fp_line
			(start 1.194308 -0.406654)
			(end 0.9144 -0.406654)
			(stroke
				(width 0.1)
				(type default)
			)
			(layer "B.Fab")
		)
		(fp_line
			(start 0.9144 0.508)
			(end 0.9144 0.406654)
			(stroke
				(width 0.1)
				(type default)
			)
			(layer "B.Fab")
		)
		(fp_line
			(start 0.9144 0.406654)
			(end 1.194308 0.406654)
			(stroke
				(width 0.1)
				(type default)
			)
			(layer "B.Fab")
		)
		(fp_line
			(start 0.9144 -0.406654)
			(end 0.9144 -0.508)
			(stroke
				(width 0.1)
				(type default)
			)
			(layer "B.Fab")
		)
		(fp_line
			(start 0.9144 -0.508)
			(end -0.9144 -0.508)
			(stroke
				(width 0.1)
				(type default)
			)
			(layer "B.Fab")
		)
		(fp_line
			(start -0.9144 0.508)
			(end 0.9144 0.508)
			(stroke
				(width 0.1)
				(type default)
			)
			(layer "B.Fab")
		)
		(fp_line
			(start -0.9144 0.4064)
			(end -0.9144 0.508)
			(stroke
				(width 0.1)
				(type default)
			)
			(layer "B.Fab")
		)
		(fp_line
			(start -0.9144 -0.406654)
			(end -1.1938 -0.406654)
			(stroke
				(width 0.1)
				(type default)
			)
			(layer "B.Fab")
		)
		(fp_line
			(start -0.9144 -0.508)
			(end -0.9144 -0.406654)
			(stroke
				(width 0.1)
				(type default)
			)
			(layer "B.Fab")
		)
		(fp_line
			(start -1.1938 0.4064)
			(end -0.9144 0.4064)
			(stroke
				(width 0.1)
				(type default)
			)
			(layer "B.Fab")
		)
		(fp_line
			(start -1.1938 -0.406654)
			(end -1.1938 0.4064)
			(stroke
				(width 0.1)
				(type default)
			)
			(layer "B.Fab")
		)
		(pad "1" smd rect
			(at 0.7366 0 90)
			(size 0.7112 0.8128)
			(layers "B.Cu" "B.Mask" "B.Paste")
			(net "P1V2_BIC_PLL")
		)
		(pad "2" smd rect
			(at -0.7366 0 90)
			(size 0.7112 0.8128)
			(layers "B.Cu" "B.Mask" "B.Paste")
			(net "P1V2_AUX")
		)
	)
	(footprint ""
		(layer "B.Cu")
		(at 156.157168 -291.72662 180)
		(property "Reference" "R3452"
			(at 0 0 0)
			(layer "B.SilkS")
			(hide yes)
			(effects
				(font
					(size 1.27 1.27)
				)
				(justify mirror)
			)
		)
		(property "Value" ""
			(at 0 0 0)
			(layer "B.Fab")
			(effects
				(font
					(size 1.27 1.27)
				)
				(justify mirror)
			)
		)
		(duplicate_pad_numbers_are_jumpers no)
		(fp_line
			(start 0.7874 0.4064)
			(end 0.7874 -0.4064)
			(stroke
				(width 0.1524)
				(type default)
			)
			(layer "B.SilkS")
		)
		(fp_line
			(start 0.7874 -0.4064)
			(end -0.7874 -0.4064)
			(stroke
				(width 0.1524)
				(type default)
			)
			(layer "B.SilkS")
		)
		(fp_line
			(start -0.7874 0.4064)
			(end 0.7874 0.4064)
			(stroke
				(width 0.1524)
				(type default)
			)
			(layer "B.SilkS")
		)
		(fp_line
			(start -0.7874 -0.4064)
			(end -0.7874 0.4064)
			(stroke
				(width 0.1524)
				(type default)
			)
			(layer "B.SilkS")
		)
		(fp_line
			(start 0.67945 0.3048)
			(end 0.67945 -0.305054)
			(stroke
				(width 0.1)
				(type default)
			)
			(layer "B.Fab")
		)
		(fp_line
			(start 0.67945 -0.305054)
			(end 0.12065 -0.305054)
			(stroke
				(width 0.1)
				(type default)
			)
			(layer "B.Fab")
		)
		(fp_line
			(start 0.12065 0.3048)
			(end 0.67945 0.3048)
			(stroke
				(width 0.1)
				(type default)
			)
			(layer "B.Fab")
		)
		(fp_line
			(start 0.12065 0.2794)
			(end 0.12065 0.3048)
			(stroke
				(width 0.1)
				(type default)
			)
			(layer "B.Fab")
		)
		(fp_line
			(start 0.12065 -0.2794)
			(end -0.12065 -0.2794)
			(stroke
				(width 0.1)
				(type default)
			)
			(layer "B.Fab")
		)
		(fp_line
			(start 0.12065 -0.305054)
			(end 0.12065 -0.2794)
			(stroke
				(width 0.1)
				(type default)
			)
			(layer "B.Fab")
		)
		(fp_line
			(start -0.120396 0.3048)
			(end -0.120396 0.2794)
			(stroke
				(width 0.1)
				(type default)
			)
			(layer "B.Fab")
		)
		(fp_line
			(start -0.120396 0.2794)
			(end 0.12065 0.2794)
			(stroke
				(width 0.1)
				(type default)
			)
			(layer "B.Fab")
		)
		(fp_line
			(start -0.12065 -0.2794)
			(end -0.12065 -0.3048)
			(stroke
				(width 0.1)
				(type default)
			)
			(layer "B.Fab")
		)
		(fp_line
			(start -0.12065 -0.3048)
			(end -0.67945 -0.3048)
			(stroke
				(width 0.1)
				(type default)
			)
			(layer "B.Fab")
		)
		(fp_line
			(start -0.67945 0.3048)
			(end -0.120396 0.3048)
			(stroke
				(width 0.1)
				(type default)
			)
			(layer "B.Fab")
		)
		(fp_line
			(start -0.67945 -0.3048)
			(end -0.67945 0.3048)
			(stroke
				(width 0.1)
				(type default)
			)
			(layer "B.Fab")
		)
		(pad "1" smd circle
			(at 0.40005 0)
			(size 0 0)
			(layers "B.Cu" "B.Mask" "B.Paste")
			(net "SPI_PEX1_CLK_R")
		)
		(pad "2" smd circle
			(at -0.40005 0)
			(size 0 0)
			(layers "B.Cu" "B.Mask" "B.Paste")
			(net "SPI_PEX1_CLK")
		)
	)
	(footprint ""
		(layer "B.Cu")
		(at 177.174906 -297.79976 -90)
		(property "Reference" "C1411"
			(at 0 0 90)
			(layer "B.SilkS")
			(hide yes)
			(effects
				(font
					(size 1.27 1.27)
				)
				(justify mirror)
			)
		)
		(property "Value" ""
			(at 0 0 90)
			(layer "B.Fab")
			(effects
				(font
					(size 1.27 1.27)
				)
				(justify mirror)
			)
		)
		(duplicate_pad_numbers_are_jumpers no)
		(fp_line
			(start -0.299974 0.150114)
			(end 0.299974 0.150114)
			(stroke
				(width 0.1)
				(type default)
			)
			(layer "B.Fab")
		)
		(fp_line
			(start 0.299974 0.150114)
			(end 0.299974 -0.150114)
			(stroke
				(width 0.1)
				(type default)
			)
			(layer "B.Fab")
		)
		(fp_line
			(start -0.299974 -0.150114)
			(end -0.299974 0.150114)
			(stroke
				(width 0.1)
				(type default)
			)
			(layer "B.Fab")
		)
		(fp_line
			(start 0.299974 -0.150114)
			(end -0.299974 -0.150114)
			(stroke
				(width 0.1)
				(type default)
			)
			(layer "B.Fab")
		)
		(pad "1" smd rect
			(at 0.2667 0 90)
			(size 0.3048 0.381)
			(layers "B.Cu" "B.Mask" "B.Paste")
			(net "P0V8_PEX1")
		)
		(pad "2" smd rect
			(at -0.2667 0 90)
			(size 0.3048 0.381)
			(layers "B.Cu" "B.Mask" "B.Paste")
			(net "GND")
		)
	)
	(footprint ""
		(layer "B.Cu")
		(at 180.50002 -299.699934 -90)
		(property "Reference" "C1460"
			(at 0 0 90)
			(layer "B.SilkS")
			(hide yes)
			(effects
				(font
					(size 1.27 1.27)
				)
				(justify mirror)
			)
		)
		(property "Value" ""
			(at 0 0 90)
			(layer "B.Fab")
			(effects
				(font
					(size 1.27 1.27)
				)
				(justify mirror)
			)
		)
		(duplicate_pad_numbers_are_jumpers no)
		(fp_line
			(start -0.299974 0.150114)
			(end 0.299974 0.150114)
			(stroke
				(width 0.1)
				(type default)
			)
			(layer "B.Fab")
		)
		(fp_line
			(start 0.299974 0.150114)
			(end 0.299974 -0.150114)
			(stroke
				(width 0.1)
				(type default)
			)
			(layer "B.Fab")
		)
		(fp_line
			(start -0.299974 -0.150114)
			(end -0.299974 0.150114)
			(stroke
				(width 0.1)
				(type default)
			)
			(layer "B.Fab")
		)
		(fp_line
			(start 0.299974 -0.150114)
			(end -0.299974 -0.150114)
			(stroke
				(width 0.1)
				(type default)
			)
			(layer "B.Fab")
		)
		(pad "1" smd rect
			(at 0.2667 0 90)
			(size 0.3048 0.381)
			(layers "B.Cu" "B.Mask" "B.Paste")
			(net "P0V8_SERDES_VDDA_PEX1")
		)
		(pad "2" smd rect
			(at -0.2667 0 90)
			(size 0.3048 0.381)
			(layers "B.Cu" "B.Mask" "B.Paste")
			(net "GND")
		)
	)
)
